(kicad_pcb
	(version 20260206)
	(generator "pcbnew")
	(generator_version "10.0")
	(general
		(thickness 1.6)
		(legacy_teardrops no)
	)
	(paper "A4")
	(title_block
		(title "9054_F0T_PDB_BD_GPU_F_V04_1213_1550_OCP.brd")
		(comment 1 "Grand Teton / footprints 160-167 of 608")
	)
	(layers
		(0 "F.Cu" signal "TOP")
		(4 "In1.Cu" signal "GND")
		(6 "In2.Cu" signal "IN1")
		(8 "In3.Cu" signal "GND1")
		(10 "In4.Cu" signal "VCC")
		(12 "In5.Cu" signal "VCC1")
		(14 "In6.Cu" signal "GND2")
		(16 "In7.Cu" signal "IN2")
		(18 "In8.Cu" signal "GND3")
		(2 "B.Cu" signal "BOTTOM")
		(9 "F.Adhes" user "F.Adhesive")
		(11 "B.Adhes" user "B.Adhesive")
		(13 "F.Paste" user "Package Geometry/Pastemask Top")
		(15 "B.Paste" user "Package Geometry/Pastemask Bottom")
		(5 "F.SilkS" user "Ref Des/Silkscreen Top")
		(7 "B.SilkS" user "Ref Des/Silkscreen Bottom")
		(1 "F.Mask" user "Board Geometry/Soldermask Top")
		(3 "B.Mask" user "Board Geometry/Soldermask Bottom")
		(17 "Dwgs.User" user "User.Drawings")
		(19 "Cmts.User" user "User.Comments")
		(21 "Eco1.User" user "User.Eco1")
		(23 "Eco2.User" user "User.Eco2")
		(25 "Edge.Cuts" user "Board Geometry/Outline")
		(27 "Margin" user)
		(31 "F.CrtYd" user "Package Geometry/Place Bound Top")
		(29 "B.CrtYd" user "Package Geometry/Place Bound Bottom")
		(35 "F.Fab" user "Ref Des/Assembly Top")
		(33 "B.Fab" user "Ref Des/Assembly Bottom")
	)
	(footprint ""
		(layer "F.Cu")
		(at 450.445632 -88.465152)
		(property "Reference" "R393"
			(at 0 0 0)
			(layer "F.SilkS")
			(hide yes)
			(effects
				(font
					(size 1.27 1.27)
				)
			)
		)
		(property "Value" ""
			(at 0 0 0)
			(layer "F.Fab")
			(effects
				(font
					(size 1.27 1.27)
				)
			)
		)
		(duplicate_pad_numbers_are_jumpers no)
		(fp_line
			(start -0.7874 -0.4064)
			(end 0.7874 -0.4064)
			(stroke
				(width 0.1524)
				(type default)
			)
			(layer "F.SilkS")
		)
		(fp_line
			(start -0.7874 0.4064)
			(end -0.7874 -0.4064)
			(stroke
				(width 0.1524)
				(type default)
			)
			(layer "F.SilkS")
		)
		(fp_line
			(start 0.7874 -0.4064)
			(end 0.7874 0.4064)
			(stroke
				(width 0.1524)
				(type default)
			)
			(layer "F.SilkS")
		)
		(fp_line
			(start 0.7874 0.4064)
			(end -0.7874 0.4064)
			(stroke
				(width 0.1524)
				(type default)
			)
			(layer "F.SilkS")
		)
		(fp_line
			(start -0.67945 -0.305054)
			(end -0.12065 -0.305054)
			(stroke
				(width 0.1)
				(type default)
			)
			(layer "F.Fab")
		)
		(fp_line
			(start -0.67945 0.3048)
			(end -0.67945 -0.305054)
			(stroke
				(width 0.1)
				(type default)
			)
			(layer "F.Fab")
		)
		(fp_line
			(start -0.12065 -0.305054)
			(end -0.12065 -0.2794)
			(stroke
				(width 0.1)
				(type default)
			)
			(layer "F.Fab")
		)
		(fp_line
			(start -0.12065 -0.2794)
			(end 0.12065 -0.2794)
			(stroke
				(width 0.1)
				(type default)
			)
			(layer "F.Fab")
		)
		(fp_line
			(start -0.12065 0.2794)
			(end -0.12065 0.3048)
			(stroke
				(width 0.1)
				(type default)
			)
			(layer "F.Fab")
		)
		(fp_line
			(start -0.12065 0.3048)
			(end -0.67945 0.3048)
			(stroke
				(width 0.1)
				(type default)
			)
			(layer "F.Fab")
		)
		(fp_line
			(start 0.120396 0.2794)
			(end -0.12065 0.2794)
			(stroke
				(width 0.1)
				(type default)
			)
			(layer "F.Fab")
		)
		(fp_line
			(start 0.120396 0.3048)
			(end 0.120396 0.2794)
			(stroke
				(width 0.1)
				(type default)
			)
			(layer "F.Fab")
		)
		(fp_line
			(start 0.12065 -0.3048)
			(end 0.67945 -0.3048)
			(stroke
				(width 0.1)
				(type default)
			)
			(layer "F.Fab")
		)
		(fp_line
			(start 0.12065 -0.2794)
			(end 0.12065 -0.3048)
			(stroke
				(width 0.1)
				(type default)
			)
			(layer "F.Fab")
		)
		(fp_line
			(start 0.67945 -0.3048)
			(end 0.67945 0.3048)
			(stroke
				(width 0.1)
				(type default)
			)
			(layer "F.Fab")
		)
		(fp_line
			(start 0.67945 0.3048)
			(end 0.120396 0.3048)
			(stroke
				(width 0.1)
				(type default)
			)
			(layer "F.Fab")
		)
		(pad "1" smd circle
			(at -0.40005 0)
			(size 0 0)
			(layers "F.Cu" "F.Mask" "F.Paste")
			(net "P3V3_HPDB_EN")
		)
		(pad "2" smd circle
			(at 0.40005 0)
			(size 0 0)
			(layers "F.Cu" "F.Mask" "F.Paste")
			(net "GND")
		)
	)
	(footprint ""
		(layer "F.Cu")
		(at 422.148 -27.94 -90)
		(property "Reference" "C94"
			(at 0 0 270)
			(layer "F.SilkS")
			(hide yes)
			(effects
				(font
					(size 1.27 1.27)
				)
			)
		)
		(property "Value" ""
			(at 0 0 270)
			(layer "F.Fab")
			(effects
				(font
					(size 1.27 1.27)
				)
			)
		)
		(duplicate_pad_numbers_are_jumpers no)
		(fp_line
			(start -0.7874 0.4064)
			(end -0.7874 -0.4064)
			(stroke
				(width 0.1524)
				(type default)
			)
			(layer "F.SilkS")
		)
		(fp_line
			(start 0.7874 0.4064)
			(end -0.7874 0.4064)
			(stroke
				(width 0.1524)
				(type default)
			)
			(layer "F.SilkS")
		)
		(fp_line
			(start -0.7874 -0.4064)
			(end 0.7874 -0.4064)
			(stroke
				(width 0.1524)
				(type default)
			)
			(layer "F.SilkS")
		)
		(fp_line
			(start 0.7874 -0.4064)
			(end 0.7874 0.4064)
			(stroke
				(width 0.1524)
				(type default)
			)
			(layer "F.SilkS")
		)
		(fp_line
			(start -0.6858 0.3048)
			(end -0.6858 -0.3048)
			(stroke
				(width 0.1)
				(type default)
			)
			(layer "F.Fab")
		)
		(fp_line
			(start -0.1016 0.3048)
			(end -0.6858 0.3048)
			(stroke
				(width 0.1)
				(type default)
			)
			(layer "F.Fab")
		)
		(fp_line
			(start 0.1016 0.3048)
			(end 0.1016 0.2794)
			(stroke
				(width 0.1)
				(type default)
			)
			(layer "F.Fab")
		)
		(fp_line
			(start 0.6858 0.3048)
			(end 0.1016 0.3048)
			(stroke
				(width 0.1)
				(type default)
			)
			(layer "F.Fab")
		)
		(fp_line
			(start -0.1016 0.2794)
			(end -0.1016 0.3048)
			(stroke
				(width 0.1)
				(type default)
			)
			(layer "F.Fab")
		)
		(fp_line
			(start 0.1016 0.2794)
			(end -0.1016 0.2794)
			(stroke
				(width 0.1)
				(type default)
			)
			(layer "F.Fab")
		)
		(fp_line
			(start -0.1016 -0.2794)
			(end 0.1016 -0.2794)
			(stroke
				(width 0.1)
				(type default)
			)
			(layer "F.Fab")
		)
		(fp_line
			(start 0.1016 -0.2794)
			(end 0.1016 -0.3048)
			(stroke
				(width 0.1)
				(type default)
			)
			(layer "F.Fab")
		)
		(fp_line
			(start -0.6858 -0.3048)
			(end -0.1016 -0.3048)
			(stroke
				(width 0.1)
				(type default)
			)
			(layer "F.Fab")
		)
		(fp_line
			(start -0.1016 -0.3048)
			(end -0.1016 -0.2794)
			(stroke
				(width 0.1)
				(type default)
			)
			(layer "F.Fab")
		)
		(fp_line
			(start 0.1016 -0.3048)
			(end 0.6858 -0.3048)
			(stroke
				(width 0.1)
				(type default)
			)
			(layer "F.Fab")
		)
		(fp_line
			(start 0.6858 -0.3048)
			(end 0.6858 0.3048)
			(stroke
				(width 0.1)
				(type default)
			)
			(layer "F.Fab")
		)
		(pad "1" smd rect
			(at -0.40005 0 90)
			(size 0.4572 0.508)
			(layers "F.Cu" "F.Mask" "F.Paste")
			(net "P12V_HPDB")
		)
		(pad "2" smd rect
			(at 0.40005 0 90)
			(size 0.4572 0.508)
			(layers "F.Cu" "F.Mask" "F.Paste")
			(net "GND")
		)
	)
	(footprint ""
		(layer "F.Cu")
		(at 140.79982 -68.199 180)
		(property "Reference" "PR6986"
			(at 0 0 180)
			(layer "F.SilkS")
			(hide yes)
			(effects
				(font
					(size 1.27 1.27)
				)
			)
		)
		(property "Value" ""
			(at 0 0 180)
			(layer "F.Fab")
			(effects
				(font
					(size 1.27 1.27)
				)
			)
		)
		(duplicate_pad_numbers_are_jumpers no)
		(fp_line
			(start 1.2954 0.5842)
			(end -1.2954 0.5842)
			(stroke
				(width 0.1524)
				(type default)
			)
			(layer "F.SilkS")
		)
		(fp_line
			(start 1.2954 -0.5842)
			(end 1.2954 0.5842)
			(stroke
				(width 0.1524)
				(type default)
			)
			(layer "F.SilkS")
		)
		(fp_line
			(start -1.2954 0.5842)
			(end -1.2954 -0.5842)
			(stroke
				(width 0.1524)
				(type default)
			)
			(layer "F.SilkS")
		)
		(fp_line
			(start -1.2954 -0.5842)
			(end 1.2954 -0.5842)
			(stroke
				(width 0.1524)
				(type default)
			)
			(layer "F.SilkS")
		)
		(fp_line
			(start 1.1938 0.4064)
			(end 0.8636 0.4064)
			(stroke
				(width 0.1)
				(type default)
			)
			(layer "F.Fab")
		)
		(fp_line
			(start 1.1938 -0.406654)
			(end 1.1938 0.4064)
			(stroke
				(width 0.1)
				(type default)
			)
			(layer "F.Fab")
		)
		(fp_line
			(start 0.8636 0.4572)
			(end -0.8636 0.4572)
			(stroke
				(width 0.1)
				(type default)
			)
			(layer "F.Fab")
		)
		(fp_line
			(start 0.8636 0.4064)
			(end 0.8636 0.4572)
			(stroke
				(width 0.1)
				(type default)
			)
			(layer "F.Fab")
		)
		(fp_line
			(start 0.8636 -0.406654)
			(end 1.1938 -0.406654)
			(stroke
				(width 0.1)
				(type default)
			)
			(layer "F.Fab")
		)
		(fp_line
			(start 0.8636 -0.4572)
			(end 0.8636 -0.406654)
			(stroke
				(width 0.1)
				(type default)
			)
			(layer "F.Fab")
		)
		(fp_line
			(start -0.8636 0.4572)
			(end -0.8636 0.4318)
			(stroke
				(width 0.1)
				(type default)
			)
			(layer "F.Fab")
		)
		(fp_line
			(start -0.8636 0.4318)
			(end -0.8636 0.4064)
			(stroke
				(width 0.1)
				(type default)
			)
			(layer "F.Fab")
		)
		(fp_line
			(start -0.8636 0.4064)
			(end -1.1938 0.4064)
			(stroke
				(width 0.1)
				(type default)
			)
			(layer "F.Fab")
		)
		(fp_line
			(start -0.8636 -0.406654)
			(end -0.8636 -0.4572)
			(stroke
				(width 0.1)
				(type default)
			)
			(layer "F.Fab")
		)
		(fp_line
			(start -0.8636 -0.4572)
			(end 0.8636 -0.4572)
			(stroke
				(width 0.1)
				(type default)
			)
			(layer "F.Fab")
		)
		(fp_line
			(start -1.1938 0.4064)
			(end -1.1938 -0.406654)
			(stroke
				(width 0.1)
				(type default)
			)
			(layer "F.Fab")
		)
		(fp_line
			(start -1.1938 -0.406654)
			(end -0.8636 -0.406654)
			(stroke
				(width 0.1)
				(type default)
			)
			(layer "F.Fab")
		)
		(pad "1" smd rect
			(at -0.7366 0 90)
			(size 0.7112 0.8128)
			(layers "F.Cu" "F.Mask" "F.Paste")
			(net "P52V_HS2_1272_S_N")
		)
		(pad "2" smd rect
			(at 0.7366 0 90)
			(size 0.7112 0.8128)
			(layers "F.Cu" "F.Mask" "F.Paste")
			(net "P52V_HS2_SENSE_N_R1")
		)
	)
	(footprint ""
		(layer "F.Cu")
		(at 436.245 -34.163)
		(property "Reference" "R23"
			(at 0 0 0)
			(layer "F.SilkS")
			(hide yes)
			(effects
				(font
					(size 1.27 1.27)
				)
			)
		)
		(property "Value" ""
			(at 0 0 0)
			(layer "F.Fab")
			(effects
				(font
					(size 1.27 1.27)
				)
			)
		)
		(duplicate_pad_numbers_are_jumpers no)
		(fp_line
			(start -0.7874 -0.4064)
			(end 0.7874 -0.4064)
			(stroke
				(width 0.1524)
				(type default)
			)
			(layer "F.SilkS")
		)
		(fp_line
			(start -0.7874 0.4064)
			(end -0.7874 -0.4064)
			(stroke
				(width 0.1524)
				(type default)
			)
			(layer "F.SilkS")
		)
		(fp_line
			(start 0.7874 -0.4064)
			(end 0.7874 0.4064)
			(stroke
				(width 0.1524)
				(type default)
			)
			(layer "F.SilkS")
		)
		(fp_line
			(start 0.7874 0.4064)
			(end -0.7874 0.4064)
			(stroke
				(width 0.1524)
				(type default)
			)
			(layer "F.SilkS")
		)
		(fp_line
			(start -0.67945 -0.305054)
			(end -0.12065 -0.305054)
			(stroke
				(width 0.1)
				(type default)
			)
			(layer "F.Fab")
		)
		(fp_line
			(start -0.67945 0.3048)
			(end -0.67945 -0.305054)
			(stroke
				(width 0.1)
				(type default)
			)
			(layer "F.Fab")
		)
		(fp_line
			(start -0.12065 -0.305054)
			(end -0.12065 -0.2794)
			(stroke
				(width 0.1)
				(type default)
			)
			(layer "F.Fab")
		)
		(fp_line
			(start -0.12065 -0.2794)
			(end 0.12065 -0.2794)
			(stroke
				(width 0.1)
				(type default)
			)
			(layer "F.Fab")
		)
		(fp_line
			(start -0.12065 0.2794)
			(end -0.12065 0.3048)
			(stroke
				(width 0.1)
				(type default)
			)
			(layer "F.Fab")
		)
		(fp_line
			(start -0.12065 0.3048)
			(end -0.67945 0.3048)
			(stroke
				(width 0.1)
				(type default)
			)
			(layer "F.Fab")
		)
		(fp_line
			(start 0.120396 0.2794)
			(end -0.12065 0.2794)
			(stroke
				(width 0.1)
				(type default)
			)
			(layer "F.Fab")
		)
		(fp_line
			(start 0.120396 0.3048)
			(end 0.120396 0.2794)
			(stroke
				(width 0.1)
				(type default)
			)
			(layer "F.Fab")
		)
		(fp_line
			(start 0.12065 -0.3048)
			(end 0.67945 -0.3048)
			(stroke
				(width 0.1)
				(type default)
			)
			(layer "F.Fab")
		)
		(fp_line
			(start 0.12065 -0.2794)
			(end 0.12065 -0.3048)
			(stroke
				(width 0.1)
				(type default)
			)
			(layer "F.Fab")
		)
		(fp_line
			(start 0.67945 -0.3048)
			(end 0.67945 0.3048)
			(stroke
				(width 0.1)
				(type default)
			)
			(layer "F.Fab")
		)
		(fp_line
			(start 0.67945 0.3048)
			(end 0.120396 0.3048)
			(stroke
				(width 0.1)
				(type default)
			)
			(layer "F.Fab")
		)
		(pad "1" smd circle
			(at -0.40005 0)
			(size 0 0)
			(layers "F.Cu" "F.Mask" "F.Paste")
			(net "P3V3_AUX")
		)
		(pad "2" smd circle
			(at 0.40005 0)
			(size 0 0)
			(layers "F.Cu" "F.Mask" "F.Paste")
			(net "PD_9543_FAN_A0")
		)
	)
	(footprint ""
		(layer "F.Cu")
		(at 434.7464 -37.211 -90)
		(property "Reference" "R11"
			(at 0 0 270)
			(layer "F.SilkS")
			(hide yes)
			(effects
				(font
					(size 1.27 1.27)
				)
			)
		)
		(property "Value" ""
			(at 0 0 270)
			(layer "F.Fab")
			(effects
				(font
					(size 1.27 1.27)
				)
			)
		)
		(duplicate_pad_numbers_are_jumpers no)
		(fp_line
			(start -0.7874 0.4064)
			(end -0.7874 -0.4064)
			(stroke
				(width 0.1524)
				(type default)
			)
			(layer "F.SilkS")
		)
		(fp_line
			(start 0.7874 0.4064)
			(end -0.7874 0.4064)
			(stroke
				(width 0.1524)
				(type default)
			)
			(layer "F.SilkS")
		)
		(fp_line
			(start -0.7874 -0.4064)
			(end 0.7874 -0.4064)
			(stroke
				(width 0.1524)
				(type default)
			)
			(layer "F.SilkS")
		)
		(fp_line
			(start 0.7874 -0.4064)
			(end 0.7874 0.4064)
			(stroke
				(width 0.1524)
				(type default)
			)
			(layer "F.SilkS")
		)
		(fp_line
			(start -0.67945 0.3048)
			(end -0.67945 -0.305054)
			(stroke
				(width 0.1)
				(type default)
			)
			(layer "F.Fab")
		)
		(fp_line
			(start -0.12065 0.3048)
			(end -0.67945 0.3048)
			(stroke
				(width 0.1)
				(type default)
			)
			(layer "F.Fab")
		)
		(fp_line
			(start 0.120396 0.3048)
			(end 0.120396 0.2794)
			(stroke
				(width 0.1)
				(type default)
			)
			(layer "F.Fab")
		)
		(fp_line
			(start 0.67945 0.3048)
			(end 0.120396 0.3048)
			(stroke
				(width 0.1)
				(type default)
			)
			(layer "F.Fab")
		)
		(fp_line
			(start -0.12065 0.2794)
			(end -0.12065 0.3048)
			(stroke
				(width 0.1)
				(type default)
			)
			(layer "F.Fab")
		)
		(fp_line
			(start 0.120396 0.2794)
			(end -0.12065 0.2794)
			(stroke
				(width 0.1)
				(type default)
			)
			(layer "F.Fab")
		)
		(fp_line
			(start -0.12065 -0.2794)
			(end 0.12065 -0.2794)
			(stroke
				(width 0.1)
				(type default)
			)
			(layer "F.Fab")
		)
		(fp_line
			(start 0.12065 -0.2794)
			(end 0.12065 -0.3048)
			(stroke
				(width 0.1)
				(type default)
			)
			(layer "F.Fab")
		)
		(fp_line
			(start 0.12065 -0.3048)
			(end 0.67945 -0.3048)
			(stroke
				(width 0.1)
				(type default)
			)
			(layer "F.Fab")
		)
		(fp_line
			(start 0.67945 -0.3048)
			(end 0.67945 0.3048)
			(stroke
				(width 0.1)
				(type default)
			)
			(layer "F.Fab")
		)
		(fp_line
			(start -0.67945 -0.305054)
			(end -0.12065 -0.305054)
			(stroke
				(width 0.1)
				(type default)
			)
			(layer "F.Fab")
		)
		(fp_line
			(start -0.12065 -0.305054)
			(end -0.12065 -0.2794)
			(stroke
				(width 0.1)
				(type default)
			)
			(layer "F.Fab")
		)
		(pad "1" smd circle
			(at -0.40005 0 270)
			(size 0 0)
			(layers "F.Cu" "F.Mask" "F.Paste")
			(net "SMB_P52V_PDB_SCL_R")
		)
		(pad "2" smd circle
			(at 0.40005 0 270)
			(size 0 0)
			(layers "F.Cu" "F.Mask" "F.Paste")
			(net "SMB_P52V_PDB_SCL")
		)
	)
	(footprint ""
		(layer "F.Cu")
		(at 456.999848 -24.500078 180)
		(property "Reference" "H16"
			(at 0.942848 10.525252 0)
			(unlocked yes)
			(layer "F.SilkS")
			(effects
				(font
					(size 0.7874 0.5842)
					(thickness 0.1524)
				)
				(justify left)
			)
		)
		(property "Value" ""
			(at 0 0 180)
			(layer "F.Fab")
			(effects
				(font
					(size 1.27 1.27)
				)
			)
		)
		(duplicate_pad_numbers_are_jumpers no)
		(pad "1" thru_hole oval
			(at 0 0 180)
			(size 9.017 14.0208)
			(drill 3.0226
				(offset 0 2.499868)
			)
			(layers "*.Cu" "*.Mask")
			(remove_unused_layers no)
			(net "GND")
			(clearance -1.500378)
			(padstack
				(mode front_inner_back)
				(layer "Inner"
					(shape circle)
					(size 0 0)
					(clearance 0)
				)
				(layer "B.Cu"
					(shape oval)
					(size 9.017 14.0208)
					(offset 0 2.499868)
					(clearance -1.500378)
				)
			)
		)
	)
	(footprint ""
		(layer "F.Cu")
		(at 397.637 -139.7)
		(property "Reference" "PC29"
			(at -7.5946 -5.30733 0)
			(unlocked yes)
			(layer "F.SilkS")
			(effects
				(font
					(size 0.7874 0.5842)
					(thickness 0.1524)
				)
				(justify left)
			)
		)
		(property "Value" ""
			(at 0 0 0)
			(layer "F.Fab")
			(effects
				(font
					(size 1.27 1.27)
				)
			)
		)
		(duplicate_pad_numbers_are_jumpers no)
		(fp_line
			(start -9.253728 3.750056)
			(end 9.249918 3.750056)
			(stroke
				(width 0.1524)
				(type default)
			)
			(layer "F.SilkS")
		)
		(fp_line
			(start 0 3.750056)
			(end -9.253728 3.750056)
			(stroke
				(width 0.1524)
				(type default)
			)
			(layer "F.SilkS")
		)
		(fp_circle
			(center 0 3.750056)
			(end 9.249918 3.750056)
			(stroke
				(width 0.1524)
				(type default)
			)
			(fill no)
			(layer "F.SilkS")
		)
		(fp_poly
			(pts
				(arc
					(start 9.249918 3.750056)
					(mid 0 12.999974)
					(end -9.249918 3.750056)
				)
			)
			(stroke
				(width 0)
				(type default)
			)
			(fill yes)
			(layer "F.SilkS")
		)
		(fp_circle
			(center 0 3.750056)
			(end 9.249918 3.750056)
			(stroke
				(width 0.1)
				(type default)
			)
			(fill no)
			(layer "F.Fab")
		)
		(pad "1" thru_hole rect
			(at 0 0)
			(size 1.778 1.778)
			(drill 1.27)
			(layers "*.Cu" "*.Mask")
			(remove_unused_layers no)
			(net "P52V_HS1")
			(clearance 0)
			(padstack
				(mode front_inner_back)
				(layer "Inner"
					(shape circle)
					(size 1.778 1.778)
					(clearance 0)
				)
				(layer "B.Cu"
					(shape rect)
					(size 1.778 1.778)
					(clearance 0)
				)
			)
		)
		(pad "2" thru_hole circle
			(at 0 7.500112)
			(size 1.778 1.778)
			(drill 1.27)
			(layers "*.Cu" "*.Mask")
			(remove_unused_layers no)
			(net "GND")
			(clearance 0)
		)
	)
	(footprint ""
		(layer "F.Cu")
		(at 378.079 -58.42)
		(property "Reference" "PC42"
			(at 5.6134 -4.67233 0)
			(unlocked yes)
			(layer "F.SilkS")
			(effects
				(font
					(size 0.7874 0.5842)
					(thickness 0.1524)
				)
				(justify left)
			)
		)
		(property "Value" ""
			(at 0 0 0)
			(layer "F.Fab")
			(effects
				(font
					(size 1.27 1.27)
				)
			)
		)
		(duplicate_pad_numbers_are_jumpers no)
		(fp_line
			(start -9.253728 3.750056)
			(end 9.249918 3.750056)
			(stroke
				(width 0.1524)
				(type default)
			)
			(layer "F.SilkS")
		)
		(fp_line
			(start 0 3.750056)
			(end -9.253728 3.750056)
			(stroke
				(width 0.1524)
				(type default)
			)
			(layer "F.SilkS")
		)
		(fp_circle
			(center 0 3.750056)
			(end 9.249918 3.750056)
			(stroke
				(width 0.1524)
				(type default)
			)
			(fill no)
			(layer "F.SilkS")
		)
		(fp_poly
			(pts
				(arc
					(start 9.249918 3.750056)
					(mid 0 12.999974)
					(end -9.249918 3.750056)
				)
			)
			(stroke
				(width 0)
				(type default)
			)
			(fill yes)
			(layer "F.SilkS")
		)
		(fp_circle
			(center 0 3.750056)
			(end 9.249918 3.750056)
			(stroke
				(width 0.1)
				(type default)
			)
			(fill no)
			(layer "F.Fab")
		)
		(pad "1" thru_hole rect
			(at 0 0)
			(size 1.778 1.778)
			(drill 1.27)
			(layers "*.Cu" "*.Mask")
			(remove_unused_layers no)
			(net "P52V_HS1")
			(clearance 0)
			(padstack
				(mode front_inner_back)
				(layer "Inner"
					(shape circle)
					(size 1.778 1.778)
					(clearance 0)
				)
				(layer "B.Cu"
					(shape rect)
					(size 1.778 1.778)
					(clearance 0)
				)
			)
		)
		(pad "2" thru_hole circle
			(at 0 7.500112)
			(size 1.778 1.778)
			(drill 1.27)
			(layers "*.Cu" "*.Mask")
			(remove_unused_layers no)
			(net "GND")
			(clearance 0)
		)
	)
)
